(kicad_pcb
	(version 20260206)
	(generator "pcbnew")
	(generator_version "10.0")
	(general
		(thickness 1.6)
		(legacy_teardrops no)
	)
	(paper "A4")
	(title_block
		(title "12092022_DA0F0TFB6D0_F0T_FAN_BOARD_MP5048_D_brd_v02_OCP.brd")
		(comment 1 "Grand Teton / footprints 458-463 of 924")
	)
	(layers
		(0 "F.Cu" signal "TOP")
		(4 "In1.Cu" signal "GND")
		(6 "In2.Cu" signal "IN1")
		(8 "In3.Cu" signal "IN2")
		(10 "In4.Cu" signal "GND1")
		(2 "B.Cu" signal "BOTTOM")
		(9 "F.Adhes" user "F.Adhesive")
		(11 "B.Adhes" user "B.Adhesive")
		(13 "F.Paste" user "Package Geometry/Pastemask Top")
		(15 "B.Paste" user "Package Geometry/Pastemask Bottom")
		(5 "F.SilkS" user "Ref Des/Silkscreen Top")
		(7 "B.SilkS" user "Ref Des/Silkscreen Bottom")
		(1 "F.Mask" user "Board Geometry/Soldermask Top")
		(3 "B.Mask" user "Board Geometry/Soldermask Bottom")
		(17 "Dwgs.User" user "User.Drawings")
		(19 "Cmts.User" user "User.Comments")
		(21 "Eco1.User" user "User.Eco1")
		(23 "Eco2.User" user "User.Eco2")
		(25 "Edge.Cuts" user "Board Geometry/Outline")
		(27 "Margin" user)
		(31 "F.CrtYd" user "Package Geometry/Place Bound Top")
		(29 "B.CrtYd" user "Package Geometry/Place Bound Bottom")
		(35 "F.Fab" user "Ref Des/Assembly Top")
		(33 "B.Fab" user "Ref Des/Assembly Bottom")
	)
	(footprint ""
		(layer "F.Cu")
		(at 10.287 -188.722)
		(property "Reference" "U59"
			(at -0.127 3.20167 0)
			(unlocked yes)
			(layer "F.SilkS")
			(effects
				(font
					(size 0.7874 0.5842)
					(thickness 0.1524)
				)
				(justify left)
			)
		)
		(property "Value" ""
			(at 0 0 0)
			(layer "F.Fab")
			(effects
				(font
					(size 1.27 1.27)
				)
			)
		)
		(duplicate_pad_numbers_are_jumpers no)
		(fp_line
			(start -1.4224 -2.5146)
			(end -1.4224 2.5146)
			(stroke
				(width 0.1524)
				(type default)
			)
			(layer "F.SilkS")
		)
		(fp_line
			(start -1.4224 2.5146)
			(end 1.4224 2.5146)
			(stroke
				(width 0.1524)
				(type default)
			)
			(layer "F.SilkS")
		)
		(fp_line
			(start -0.4572 -2.5146)
			(end -1.4224 -2.5146)
			(stroke
				(width 0.1524)
				(type default)
			)
			(layer "F.SilkS")
		)
		(fp_line
			(start 0 -2.0574)
			(end -0.4572 -2.5146)
			(stroke
				(width 0.1524)
				(type default)
			)
			(layer "F.SilkS")
		)
		(fp_line
			(start 0.4572 -2.5146)
			(end 0 -2.0574)
			(stroke
				(width 0.1524)
				(type default)
			)
			(layer "F.SilkS")
		)
		(fp_line
			(start 1.4224 -2.5146)
			(end 0.4572 -2.5146)
			(stroke
				(width 0.1524)
				(type default)
			)
			(layer "F.SilkS")
		)
		(fp_line
			(start 1.4224 2.5146)
			(end 1.4224 -2.5146)
			(stroke
				(width 0.1524)
				(type default)
			)
			(layer "F.SilkS")
		)
		(fp_poly
			(pts
				(xy -2.702814 -2.4892) (xy -3.083814 -3.2512) (xy -2.321814 -3.2512)
			)
			(stroke
				(width 0)
				(type default)
			)
			(fill yes)
			(layer "F.SilkS")
		)
		(fp_line
			(start -2.648712 -2.114804)
			(end -2.648712 2.112264)
			(stroke
				(width 0.1)
				(type default)
			)
			(layer "F.Fab")
		)
		(fp_line
			(start -2.648712 2.112264)
			(end -2.0066 2.112264)
			(stroke
				(width 0.1)
				(type default)
			)
			(layer "F.Fab")
		)
		(fp_line
			(start -2.0066 -2.5146)
			(end -2.0066 -2.114804)
			(stroke
				(width 0.1)
				(type default)
			)
			(layer "F.Fab")
		)
		(fp_line
			(start -2.0066 -2.114804)
			(end -2.648712 -2.114804)
			(stroke
				(width 0.1)
				(type default)
			)
			(layer "F.Fab")
		)
		(fp_line
			(start -2.0066 2.112264)
			(end -2.0066 2.5146)
			(stroke
				(width 0.1)
				(type default)
			)
			(layer "F.Fab")
		)
		(fp_line
			(start -2.0066 2.5146)
			(end 2.0066 2.5146)
			(stroke
				(width 0.1)
				(type default)
			)
			(layer "F.Fab")
		)
		(fp_line
			(start 2.0066 -2.5146)
			(end -2.0066 -2.5146)
			(stroke
				(width 0.1)
				(type default)
			)
			(layer "F.Fab")
		)
		(fp_line
			(start 2.0066 -2.112264)
			(end 2.0066 -2.5146)
			(stroke
				(width 0.1)
				(type default)
			)
			(layer "F.Fab")
		)
		(fp_line
			(start 2.0066 2.112264)
			(end 2.642616 2.112264)
			(stroke
				(width 0.1)
				(type default)
			)
			(layer "F.Fab")
		)
		(fp_line
			(start 2.0066 2.5146)
			(end 2.0066 2.112264)
			(stroke
				(width 0.1)
				(type default)
			)
			(layer "F.Fab")
		)
		(fp_line
			(start 2.642616 -2.112264)
			(end 2.0066 -2.112264)
			(stroke
				(width 0.1)
				(type default)
			)
			(layer "F.Fab")
		)
		(fp_line
			(start 2.642616 2.112264)
			(end 2.642616 -2.112264)
			(stroke
				(width 0.1)
				(type default)
			)
			(layer "F.Fab")
		)
		(fp_poly
			(pts
				(xy -3.6322 -1.869186) (xy -4.3942 -1.488186) (xy -4.3942 -2.250186)
			)
			(stroke
				(width 0)
				(type default)
			)
			(fill yes)
			(layer "F.Fab")
		)
		(pad "1" smd rect
			(at -2.6416 -1.905 270)
			(size 0.5588 1.7272)
			(layers "F.Cu" "F.Mask" "F.Paste")
			(net "FRU_ADDR0")
		)
		(pad "2" smd rect
			(at -2.6416 -0.635 270)
			(size 0.5588 1.7272)
			(layers "F.Cu" "F.Mask" "F.Paste")
			(net "FRU_ADDR1")
		)
		(pad "3" smd rect
			(at -2.6416 0.635 270)
			(size 0.5588 1.7272)
			(layers "F.Cu" "F.Mask" "F.Paste")
			(net "FRU_ADDR2")
		)
		(pad "4" smd rect
			(at -2.6416 1.905 270)
			(size 0.5588 1.7272)
			(layers "F.Cu" "F.Mask" "F.Paste")
			(net "GND")
		)
		(pad "5" smd rect
			(at 2.6416 1.905 270)
			(size 0.5588 1.7272)
			(layers "F.Cu" "F.Mask" "F.Paste")
			(net "SMB_FRU_DAT")
		)
		(pad "6" smd rect
			(at 2.6416 0.635 270)
			(size 0.5588 1.7272)
			(layers "F.Cu" "F.Mask" "F.Paste")
			(net "SMB_FRU_CLK")
		)
		(pad "7" smd rect
			(at 2.6416 -0.635 270)
			(size 0.5588 1.7272)
			(layers "F.Cu" "F.Mask" "F.Paste")
			(net "FRU_WP_N")
		)
		(pad "8" smd rect
			(at 2.6416 -1.905 270)
			(size 0.5588 1.7272)
			(layers "F.Cu" "F.Mask" "F.Paste")
			(net "P3V3_AUX")
		)
	)
	(footprint ""
		(layer "F.Cu")
		(at 20.828 -133.985 -90)
		(property "Reference" "R4849"
			(at 0 0 270)
			(layer "F.SilkS")
			(hide yes)
			(effects
				(font
					(size 1.27 1.27)
				)
			)
		)
		(property "Value" ""
			(at 0 0 270)
			(layer "F.Fab")
			(effects
				(font
					(size 1.27 1.27)
				)
			)
		)
		(duplicate_pad_numbers_are_jumpers no)
		(fp_line
			(start -0.7874 0.4064)
			(end -0.7874 -0.4064)
			(stroke
				(width 0.1524)
				(type default)
			)
			(layer "F.SilkS")
		)
		(fp_line
			(start 0.7874 0.4064)
			(end -0.7874 0.4064)
			(stroke
				(width 0.1524)
				(type default)
			)
			(layer "F.SilkS")
		)
		(fp_line
			(start -0.7874 -0.4064)
			(end 0.7874 -0.4064)
			(stroke
				(width 0.1524)
				(type default)
			)
			(layer "F.SilkS")
		)
		(fp_line
			(start 0.7874 -0.4064)
			(end 0.7874 0.4064)
			(stroke
				(width 0.1524)
				(type default)
			)
			(layer "F.SilkS")
		)
		(fp_line
			(start -0.67945 0.3048)
			(end -0.67945 -0.305054)
			(stroke
				(width 0.1)
				(type default)
			)
			(layer "F.Fab")
		)
		(fp_line
			(start -0.12065 0.3048)
			(end -0.67945 0.3048)
			(stroke
				(width 0.1)
				(type default)
			)
			(layer "F.Fab")
		)
		(fp_line
			(start 0.120396 0.3048)
			(end 0.120396 0.2794)
			(stroke
				(width 0.1)
				(type default)
			)
			(layer "F.Fab")
		)
		(fp_line
			(start 0.67945 0.3048)
			(end 0.120396 0.3048)
			(stroke
				(width 0.1)
				(type default)
			)
			(layer "F.Fab")
		)
		(fp_line
			(start -0.12065 0.2794)
			(end -0.12065 0.3048)
			(stroke
				(width 0.1)
				(type default)
			)
			(layer "F.Fab")
		)
		(fp_line
			(start 0.120396 0.2794)
			(end -0.12065 0.2794)
			(stroke
				(width 0.1)
				(type default)
			)
			(layer "F.Fab")
		)
		(fp_line
			(start -0.12065 -0.2794)
			(end 0.12065 -0.2794)
			(stroke
				(width 0.1)
				(type default)
			)
			(layer "F.Fab")
		)
		(fp_line
			(start 0.12065 -0.2794)
			(end 0.12065 -0.3048)
			(stroke
				(width 0.1)
				(type default)
			)
			(layer "F.Fab")
		)
		(fp_line
			(start 0.12065 -0.3048)
			(end 0.67945 -0.3048)
			(stroke
				(width 0.1)
				(type default)
			)
			(layer "F.Fab")
		)
		(fp_line
			(start 0.67945 -0.3048)
			(end 0.67945 0.3048)
			(stroke
				(width 0.1)
				(type default)
			)
			(layer "F.Fab")
		)
		(fp_line
			(start -0.67945 -0.305054)
			(end -0.12065 -0.305054)
			(stroke
				(width 0.1)
				(type default)
			)
			(layer "F.Fab")
		)
		(fp_line
			(start -0.12065 -0.305054)
			(end -0.12065 -0.2794)
			(stroke
				(width 0.1)
				(type default)
			)
			(layer "F.Fab")
		)
		(pad "1" smd circle
			(at -0.40005 0 270)
			(size 0 0)
			(layers "F.Cu" "F.Mask" "F.Paste")
			(net "P3V3_AUX")
		)
		(pad "2" smd circle
			(at 0.40005 0 270)
			(size 0 0)
			(layers "F.Cu" "F.Mask" "F.Paste")
			(net "MAX31790_U330_ADD1")
		)
	)
	(footprint ""
		(layer "F.Cu")
		(at 18.288 -160.02 -90)
		(property "Reference" "R5463"
			(at 0 0 270)
			(layer "F.SilkS")
			(hide yes)
			(effects
				(font
					(size 1.27 1.27)
				)
			)
		)
		(property "Value" ""
			(at 0 0 270)
			(layer "F.Fab")
			(effects
				(font
					(size 1.27 1.27)
				)
			)
		)
		(duplicate_pad_numbers_are_jumpers no)
		(fp_line
			(start -0.7874 0.4064)
			(end -0.7874 -0.4064)
			(stroke
				(width 0.1524)
				(type default)
			)
			(layer "F.SilkS")
		)
		(fp_line
			(start 0.7874 0.4064)
			(end -0.7874 0.4064)
			(stroke
				(width 0.1524)
				(type default)
			)
			(layer "F.SilkS")
		)
		(fp_line
			(start -0.7874 -0.4064)
			(end 0.7874 -0.4064)
			(stroke
				(width 0.1524)
				(type default)
			)
			(layer "F.SilkS")
		)
		(fp_line
			(start 0.7874 -0.4064)
			(end 0.7874 0.4064)
			(stroke
				(width 0.1524)
				(type default)
			)
			(layer "F.SilkS")
		)
		(fp_line
			(start -0.67945 0.3048)
			(end -0.67945 -0.305054)
			(stroke
				(width 0.1)
				(type default)
			)
			(layer "F.Fab")
		)
		(fp_line
			(start -0.12065 0.3048)
			(end -0.67945 0.3048)
			(stroke
				(width 0.1)
				(type default)
			)
			(layer "F.Fab")
		)
		(fp_line
			(start 0.120396 0.3048)
			(end 0.120396 0.2794)
			(stroke
				(width 0.1)
				(type default)
			)
			(layer "F.Fab")
		)
		(fp_line
			(start 0.67945 0.3048)
			(end 0.120396 0.3048)
			(stroke
				(width 0.1)
				(type default)
			)
			(layer "F.Fab")
		)
		(fp_line
			(start -0.12065 0.2794)
			(end -0.12065 0.3048)
			(stroke
				(width 0.1)
				(type default)
			)
			(layer "F.Fab")
		)
		(fp_line
			(start 0.120396 0.2794)
			(end -0.12065 0.2794)
			(stroke
				(width 0.1)
				(type default)
			)
			(layer "F.Fab")
		)
		(fp_line
			(start -0.12065 -0.2794)
			(end 0.12065 -0.2794)
			(stroke
				(width 0.1)
				(type default)
			)
			(layer "F.Fab")
		)
		(fp_line
			(start 0.12065 -0.2794)
			(end 0.12065 -0.3048)
			(stroke
				(width 0.1)
				(type default)
			)
			(layer "F.Fab")
		)
		(fp_line
			(start 0.12065 -0.3048)
			(end 0.67945 -0.3048)
			(stroke
				(width 0.1)
				(type default)
			)
			(layer "F.Fab")
		)
		(fp_line
			(start 0.67945 -0.3048)
			(end 0.67945 0.3048)
			(stroke
				(width 0.1)
				(type default)
			)
			(layer "F.Fab")
		)
		(fp_line
			(start -0.67945 -0.305054)
			(end -0.12065 -0.305054)
			(stroke
				(width 0.1)
				(type default)
			)
			(layer "F.Fab")
		)
		(fp_line
			(start -0.12065 -0.305054)
			(end -0.12065 -0.2794)
			(stroke
				(width 0.1)
				(type default)
			)
			(layer "F.Fab")
		)
		(pad "1" smd circle
			(at -0.40005 0 270)
			(size 0 0)
			(layers "F.Cu" "F.Mask" "F.Paste")
			(net "SMB_PDBV_FAN_SCL")
		)
		(pad "2" smd circle
			(at 0.40005 0 270)
			(size 0 0)
			(layers "F.Cu" "F.Mask" "F.Paste")
			(net "SMB_PDBV_FAN_R_U321_SCL")
		)
	)
	(footprint ""
		(layer "F.Cu")
		(at 11.445494 -70.542912 180)
		(property "Reference" "R5356"
			(at 0 0 180)
			(layer "F.SilkS")
			(hide yes)
			(effects
				(font
					(size 1.27 1.27)
				)
			)
		)
		(property "Value" ""
			(at 0 0 180)
			(layer "F.Fab")
			(effects
				(font
					(size 1.27 1.27)
				)
			)
		)
		(duplicate_pad_numbers_are_jumpers no)
		(fp_line
			(start 0.7874 0.4064)
			(end -0.7874 0.4064)
			(stroke
				(width 0.1524)
				(type default)
			)
			(layer "F.SilkS")
		)
		(fp_line
			(start 0.7874 -0.4064)
			(end 0.7874 0.4064)
			(stroke
				(width 0.1524)
				(type default)
			)
			(layer "F.SilkS")
		)
		(fp_line
			(start -0.7874 0.4064)
			(end -0.7874 -0.4064)
			(stroke
				(width 0.1524)
				(type default)
			)
			(layer "F.SilkS")
		)
		(fp_line
			(start -0.7874 -0.4064)
			(end 0.7874 -0.4064)
			(stroke
				(width 0.1524)
				(type default)
			)
			(layer "F.SilkS")
		)
		(fp_line
			(start 0.67945 0.3048)
			(end 0.120396 0.3048)
			(stroke
				(width 0.1)
				(type default)
			)
			(layer "F.Fab")
		)
		(fp_line
			(start 0.67945 -0.3048)
			(end 0.67945 0.3048)
			(stroke
				(width 0.1)
				(type default)
			)
			(layer "F.Fab")
		)
		(fp_line
			(start 0.12065 -0.2794)
			(end 0.12065 -0.3048)
			(stroke
				(width 0.1)
				(type default)
			)
			(layer "F.Fab")
		)
		(fp_line
			(start 0.12065 -0.3048)
			(end 0.67945 -0.3048)
			(stroke
				(width 0.1)
				(type default)
			)
			(layer "F.Fab")
		)
		(fp_line
			(start 0.120396 0.3048)
			(end 0.120396 0.2794)
			(stroke
				(width 0.1)
				(type default)
			)
			(layer "F.Fab")
		)
		(fp_line
			(start 0.120396 0.2794)
			(end -0.12065 0.2794)
			(stroke
				(width 0.1)
				(type default)
			)
			(layer "F.Fab")
		)
		(fp_line
			(start -0.12065 0.3048)
			(end -0.67945 0.3048)
			(stroke
				(width 0.1)
				(type default)
			)
			(layer "F.Fab")
		)
		(fp_line
			(start -0.12065 0.2794)
			(end -0.12065 0.3048)
			(stroke
				(width 0.1)
				(type default)
			)
			(layer "F.Fab")
		)
		(fp_line
			(start -0.12065 -0.2794)
			(end 0.12065 -0.2794)
			(stroke
				(width 0.1)
				(type default)
			)
			(layer "F.Fab")
		)
		(fp_line
			(start -0.12065 -0.305054)
			(end -0.12065 -0.2794)
			(stroke
				(width 0.1)
				(type default)
			)
			(layer "F.Fab")
		)
		(fp_line
			(start -0.67945 0.3048)
			(end -0.67945 -0.305054)
			(stroke
				(width 0.1)
				(type default)
			)
			(layer "F.Fab")
		)
		(fp_line
			(start -0.67945 -0.305054)
			(end -0.12065 -0.305054)
			(stroke
				(width 0.1)
				(type default)
			)
			(layer "F.Fab")
		)
		(pad "1" smd circle
			(at -0.40005 0 180)
			(size 0 0)
			(layers "F.Cu" "F.Mask" "F.Paste")
			(net "FAN_5_ON")
		)
		(pad "2" smd circle
			(at 0.40005 0 180)
			(size 0 0)
			(layers "F.Cu" "F.Mask" "F.Paste")
			(net "P52V_FAN_5_EN")
		)
	)
	(footprint ""
		(layer "F.Cu")
		(at 14.859 -124.587)
		(property "Reference" "R5611"
			(at 0 0 0)
			(layer "F.SilkS")
			(hide yes)
			(effects
				(font
					(size 1.27 1.27)
				)
			)
		)
		(property "Value" ""
			(at 0 0 0)
			(layer "F.Fab")
			(effects
				(font
					(size 1.27 1.27)
				)
			)
		)
		(duplicate_pad_numbers_are_jumpers no)
		(fp_line
			(start -0.7874 -0.4064)
			(end 0.7874 -0.4064)
			(stroke
				(width 0.1524)
				(type default)
			)
			(layer "F.SilkS")
		)
		(fp_line
			(start -0.7874 0.4064)
			(end -0.7874 -0.4064)
			(stroke
				(width 0.1524)
				(type default)
			)
			(layer "F.SilkS")
		)
		(fp_line
			(start 0.7874 -0.4064)
			(end 0.7874 0.4064)
			(stroke
				(width 0.1524)
				(type default)
			)
			(layer "F.SilkS")
		)
		(fp_line
			(start 0.7874 0.4064)
			(end -0.7874 0.4064)
			(stroke
				(width 0.1524)
				(type default)
			)
			(layer "F.SilkS")
		)
		(fp_line
			(start -0.67945 -0.305054)
			(end -0.12065 -0.305054)
			(stroke
				(width 0.1)
				(type default)
			)
			(layer "F.Fab")
		)
		(fp_line
			(start -0.67945 0.3048)
			(end -0.67945 -0.305054)
			(stroke
				(width 0.1)
				(type default)
			)
			(layer "F.Fab")
		)
		(fp_line
			(start -0.12065 -0.305054)
			(end -0.12065 -0.2794)
			(stroke
				(width 0.1)
				(type default)
			)
			(layer "F.Fab")
		)
		(fp_line
			(start -0.12065 -0.2794)
			(end 0.12065 -0.2794)
			(stroke
				(width 0.1)
				(type default)
			)
			(layer "F.Fab")
		)
		(fp_line
			(start -0.12065 0.2794)
			(end -0.12065 0.3048)
			(stroke
				(width 0.1)
				(type default)
			)
			(layer "F.Fab")
		)
		(fp_line
			(start -0.12065 0.3048)
			(end -0.67945 0.3048)
			(stroke
				(width 0.1)
				(type default)
			)
			(layer "F.Fab")
		)
		(fp_line
			(start 0.120396 0.2794)
			(end -0.12065 0.2794)
			(stroke
				(width 0.1)
				(type default)
			)
			(layer "F.Fab")
		)
		(fp_line
			(start 0.120396 0.3048)
			(end 0.120396 0.2794)
			(stroke
				(width 0.1)
				(type default)
			)
			(layer "F.Fab")
		)
		(fp_line
			(start 0.12065 -0.3048)
			(end 0.67945 -0.3048)
			(stroke
				(width 0.1)
				(type default)
			)
			(layer "F.Fab")
		)
		(fp_line
			(start 0.12065 -0.2794)
			(end 0.12065 -0.3048)
			(stroke
				(width 0.1)
				(type default)
			)
			(layer "F.Fab")
		)
		(fp_line
			(start 0.67945 -0.3048)
			(end 0.67945 0.3048)
			(stroke
				(width 0.1)
				(type default)
			)
			(layer "F.Fab")
		)
		(fp_line
			(start 0.67945 0.3048)
			(end 0.120396 0.3048)
			(stroke
				(width 0.1)
				(type default)
			)
			(layer "F.Fab")
		)
		(pad "1" smd rect
			(at -0.40005 0 180)
			(size 0.4572 0.508)
			(layers "F.Cu" "F.Mask" "F.Paste")
			(net "FAN_5_TACH_IL")
		)
		(pad "2" smd rect
			(at 0.40005 0 180)
			(size 0.4572 0.508)
			(layers "F.Cu" "F.Mask" "F.Paste")
			(net "FAN_5_TACH_IL_R1")
		)
	)
	(footprint ""
		(layer "F.Cu")
		(at 34.417 -291.084)
		(property "Reference" "U368"
			(at -3.556 -1.75133 0)
			(unlocked yes)
			(layer "F.SilkS")
			(effects
				(font
					(size 0.7874 0.5842)
					(thickness 0.1524)
				)
				(justify left)
			)
		)
		(property "Value" ""
			(at 0 0 0)
			(layer "F.Fab")
			(effects
				(font
					(size 1.27 1.27)
				)
			)
		)
		(duplicate_pad_numbers_are_jumpers no)
		(fp_line
			(start -1.335278 -1.100074)
			(end -1.335278 1.100074)
			(stroke
				(width 0.1524)
				(type default)
			)
			(layer "F.SilkS")
		)
		(fp_line
			(start -1.335278 1.100074)
			(end 1.335278 1.100074)
			(stroke
				(width 0.1524)
				(type default)
			)
			(layer "F.SilkS")
		)
		(fp_line
			(start 1.335278 -1.100074)
			(end -1.335278 -1.100074)
			(stroke
				(width 0.1524)
				(type default)
			)
			(layer "F.SilkS")
		)
		(fp_line
			(start 1.335278 1.100074)
			(end 1.335278 -1.100074)
			(stroke
				(width 0.1524)
				(type default)
			)
			(layer "F.SilkS")
		)
		(fp_line
			(start -0.674878 -1.100074)
			(end -0.674878 1.100074)
			(stroke
				(width 0.1)
				(type default)
			)
			(layer "F.Fab")
		)
		(fp_line
			(start -0.674878 1.100074)
			(end 0.674878 1.100074)
			(stroke
				(width 0.1)
				(type default)
			)
			(layer "F.Fab")
		)
		(fp_line
			(start 0.674878 -1.100074)
			(end -0.674878 -1.100074)
			(stroke
				(width 0.1)
				(type default)
			)
			(layer "F.Fab")
		)
		(fp_line
			(start 0.674878 1.100074)
			(end 0.674878 -1.100074)
			(stroke
				(width 0.1)
				(type default)
			)
			(layer "F.Fab")
		)
		(pad "D" smd rect
			(at 0.8001 0 270)
			(size 0.6096 0.8128)
			(layers "F.Cu" "F.Mask" "F.Paste")
			(net "FAN_0_OK_LED_R_N")
		)
		(pad "G" smd rect
			(at -0.8001 -0.649986 270)
			(size 0.6096 0.8128)
			(layers "F.Cu" "F.Mask" "F.Paste")
			(net "FAN_0_OK_R_LED")
		)
		(pad "S" smd rect
			(at -0.8001 0.649986 270)
			(size 0.6096 0.8128)
			(layers "F.Cu" "F.Mask" "F.Paste")
			(net "GND")
		)
	)
)
